(kicad_pcb
	(version 20260206)
	(generator "pcbnew")
	(generator_version "10.0")
	(general
		(thickness 1.6)
		(legacy_teardrops no)
	)
	(paper "A4")
	(title_block
		(title "Wiwynn_Tioga_Pass_MB.brd")
		(comment 1 "Tioga Pass / footprints 1655-1662 of 4770")
	)
	(layers
		(0 "F.Cu" signal "TOP")
		(4 "In1.Cu" signal "L2GND")
		(6 "In2.Cu" signal "L3")
		(8 "In3.Cu" signal "L4GND")
		(10 "In4.Cu" signal "L5")
		(12 "In5.Cu" signal "L6GND")
		(14 "In6.Cu" signal "L7VCC")
		(16 "In7.Cu" signal "L8VCC")
		(18 "In8.Cu" signal "L9GND")
		(20 "In9.Cu" signal "L10")
		(22 "In10.Cu" signal "L11GND")
		(24 "In11.Cu" signal "L12")
		(26 "In12.Cu" signal "L13GND")
		(2 "B.Cu" signal "BOTTOM")
		(9 "F.Adhes" user "F.Adhesive")
		(11 "B.Adhes" user "B.Adhesive")
		(13 "F.Paste" user "Package Geometry/Pastemask Top")
		(15 "B.Paste" user "Package Geometry/Pastemask Bottom")
		(5 "F.SilkS" user "Ref Des/Silkscreen Top")
		(7 "B.SilkS" user "Ref Des/Silkscreen Bottom")
		(1 "F.Mask" user "Board Geometry/Soldermask Top")
		(3 "B.Mask" user "Board Geometry/Soldermask Bottom")
		(17 "Dwgs.User" user "User.Drawings")
		(19 "Cmts.User" user "User.Comments")
		(21 "Eco1.User" user "User.Eco1")
		(23 "Eco2.User" user "User.Eco2")
		(25 "Edge.Cuts" user "Board Geometry/Outline")
		(27 "Margin" user)
		(31 "F.CrtYd" user "Package Geometry/Place Bound Top")
		(29 "B.CrtYd" user "Package Geometry/Place Bound Bottom")
		(35 "F.Fab" user "Ref Des/Assembly Top")
		(33 "B.Fab" user "Ref Des/Assembly Bottom")
	)
	(footprint ""
		(layer "F.Cu")
		(at 401.472146 -37.220652 90)
		(property "Reference" "R6W17"
			(at -0.8382 -0.67818 90)
			(unlocked yes)
			(layer "F.SilkS")
			(effects
				(font
					(size 0.4064 0.254)
					(thickness 0.1524)
				)
				(justify left)
			)
		)
		(property "Value" ""
			(at 0 0 90)
			(layer "F.Fab")
			(effects
				(font
					(size 1.27 1.27)
				)
			)
		)
		(duplicate_pad_numbers_are_jumpers no)
		(fp_poly
			(pts
				(xy -0.2794 -0.1016) (xy 0.2794 -0.1016) (xy 0.2794 0.9906) (xy -0.2794 0.9906)
			)
			(stroke
				(width 0)
				(type default)
			)
			(fill no)
			(layer "F.CrtYd")
		)
		(fp_line
			(start 0.2794 -0.1016)
			(end -0.2794 -0.1016)
			(stroke
				(width 0.1)
				(type default)
			)
			(layer "F.Fab")
		)
		(fp_line
			(start -0.2794 -0.1016)
			(end -0.2794 0.9906)
			(stroke
				(width 0.1)
				(type default)
			)
			(layer "F.Fab")
		)
		(fp_line
			(start 0.2794 0.9906)
			(end 0.2794 -0.1016)
			(stroke
				(width 0.1)
				(type default)
			)
			(layer "F.Fab")
		)
		(fp_line
			(start -0.2794 0.9906)
			(end 0.2794 0.9906)
			(stroke
				(width 0.1)
				(type default)
			)
			(layer "F.Fab")
		)
		(pad "1" smd rect
			(at 0 0 90)
			(size 0.508 0.508)
			(layers "F.Cu" "F.Mask" "F.Paste")
			(net "SMB_DEBUG_STBY_LVC3_SCL")
		)
		(pad "2" smd rect
			(at 0 0.889 90)
			(size 0.508 0.508)
			(layers "F.Cu" "F.Mask" "F.Paste")
			(net "SMB_DEBUG_STBY_LVC3_SCL_R")
		)
		(zone
			(layer "F.Cu")
			(hatch none 0.5)
			(connect_pads
				(clearance 0)
			)
			(min_thickness 0.25)
			(keepout
				(tracks allowed)
				(vias not_allowed)
				(pads allowed)
				(copperpour not_allowed)
				(footprints allowed)
			)
			(placement
				(enabled no)
				(sheetname "")
			)
			(fill
				(thermal_gap 0.5)
				(thermal_bridge_width 0.5)
				(island_removal_mode 0)
			)
			(polygon
				(pts
					(xy 401.726146 -36.966652) (xy 401.726146 -37.474652) (xy 402.107146 -37.474652) (xy 402.107146 -36.966652)
				)
			)
		)
		(zone
			(layer "F.Cu")
			(hatch none 0.5)
			(connect_pads
				(clearance 0)
			)
			(min_thickness 0.25)
			(keepout
				(tracks not_allowed)
				(vias allowed)
				(pads allowed)
				(copperpour not_allowed)
				(footprints allowed)
			)
			(placement
				(enabled no)
				(sheetname "")
			)
			(fill
				(thermal_gap 0.5)
				(thermal_bridge_width 0.5)
				(island_removal_mode 0)
			)
			(polygon
				(pts
					(xy 402.107146 -36.966652) (xy 402.107146 -37.474652) (xy 401.726146 -37.474652) (xy 401.726146 -36.966652)
				)
			)
		)
	)
	(footprint ""
		(layer "F.Cu")
		(at 325.0057 -31.15818)
		(property "Reference" "C6F2"
			(at 0 0 0)
			(layer "F.SilkS")
			(hide yes)
			(effects
				(font
					(size 1.27 1.27)
				)
			)
		)
		(property "Value" ""
			(at 0 0 0)
			(layer "F.Fab")
			(effects
				(font
					(size 1.27 1.27)
				)
			)
		)
		(duplicate_pad_numbers_are_jumpers no)
		(fp_poly
			(pts
				(xy 0.3048 -0.1016) (xy 0.3048 0.9906) (xy -0.3048 0.9906) (xy -0.3048 -0.1016)
			)
			(stroke
				(width 0)
				(type default)
			)
			(fill no)
			(layer "F.CrtYd")
		)
		(fp_line
			(start -0.3048 -0.1016)
			(end -0.3048 0.9906)
			(stroke
				(width 0.1)
				(type default)
			)
			(layer "F.Fab")
		)
		(fp_line
			(start -0.3048 0.9906)
			(end 0.3048 0.9906)
			(stroke
				(width 0.1)
				(type default)
			)
			(layer "F.Fab")
		)
		(fp_line
			(start 0.3048 -0.1016)
			(end -0.3048 -0.1016)
			(stroke
				(width 0.1)
				(type default)
			)
			(layer "F.Fab")
		)
		(fp_line
			(start 0.3048 0.9906)
			(end 0.3048 -0.1016)
			(stroke
				(width 0.1)
				(type default)
			)
			(layer "F.Fab")
		)
		(pad "1" smd rect
			(at 0 0)
			(size 0.508 0.508)
			(layers "F.Cu" "F.Mask" "F.Paste")
			(net "PVCCIO_CPU0")
		)
		(pad "2" smd rect
			(at 0 0.889)
			(size 0.508 0.508)
			(layers "F.Cu" "F.Mask" "F.Paste")
			(net "GND")
		)
		(zone
			(layer "F.Cu")
			(hatch none 0.5)
			(connect_pads
				(clearance 0)
			)
			(min_thickness 0.25)
			(keepout
				(tracks allowed)
				(vias not_allowed)
				(pads allowed)
				(copperpour not_allowed)
				(footprints allowed)
			)
			(placement
				(enabled no)
				(sheetname "")
			)
			(fill
				(thermal_gap 0.5)
				(thermal_bridge_width 0.5)
				(island_removal_mode 0)
			)
			(polygon
				(pts
					(xy 324.7517 -30.90418) (xy 325.2597 -30.90418) (xy 325.2597 -30.52318) (xy 324.7517 -30.52318)
				)
			)
		)
		(zone
			(layer "F.Cu")
			(hatch none 0.5)
			(connect_pads
				(clearance 0)
			)
			(min_thickness 0.25)
			(keepout
				(tracks not_allowed)
				(vias allowed)
				(pads allowed)
				(copperpour not_allowed)
				(footprints allowed)
			)
			(placement
				(enabled no)
				(sheetname "")
			)
			(fill
				(thermal_gap 0.5)
				(thermal_bridge_width 0.5)
				(island_removal_mode 0)
			)
			(polygon
				(pts
					(xy 324.7517 -30.52318) (xy 325.2597 -30.52318) (xy 325.2597 -30.90418) (xy 324.7517 -30.90418)
				)
			)
		)
	)
	(footprint ""
		(layer "F.Cu")
		(at 408.161236 -47.825914 180)
		(property "Reference" "R1T12"
			(at 0 0 180)
			(layer "F.SilkS")
			(hide yes)
			(effects
				(font
					(size 1.27 1.27)
				)
			)
		)
		(property "Value" ""
			(at 0 0 180)
			(layer "F.Fab")
			(effects
				(font
					(size 1.27 1.27)
				)
			)
		)
		(duplicate_pad_numbers_are_jumpers no)
		(fp_poly
			(pts
				(xy -0.2794 -0.1016) (xy 0.2794 -0.1016) (xy 0.2794 0.9906) (xy -0.2794 0.9906)
			)
			(stroke
				(width 0)
				(type default)
			)
			(fill no)
			(layer "F.CrtYd")
		)
		(fp_line
			(start 0.2794 0.9906)
			(end 0.2794 -0.1016)
			(stroke
				(width 0.1)
				(type default)
			)
			(layer "F.Fab")
		)
		(fp_line
			(start 0.2794 -0.1016)
			(end -0.2794 -0.1016)
			(stroke
				(width 0.1)
				(type default)
			)
			(layer "F.Fab")
		)
		(fp_line
			(start -0.2794 0.9906)
			(end 0.2794 0.9906)
			(stroke
				(width 0.1)
				(type default)
			)
			(layer "F.Fab")
		)
		(fp_line
			(start -0.2794 -0.1016)
			(end -0.2794 0.9906)
			(stroke
				(width 0.1)
				(type default)
			)
			(layer "F.Fab")
		)
		(pad "1" smd rect
			(at 0 0 180)
			(size 0.508 0.508)
			(layers "F.Cu" "F.Mask" "F.Paste")
			(net "FM_BOARD_REV_ID1")
		)
		(pad "2" smd rect
			(at 0 0.889 180)
			(size 0.508 0.508)
			(layers "F.Cu" "F.Mask" "F.Paste")
			(net "GND")
		)
	)
	(footprint ""
		(layer "F.Cu")
		(at 171.99991 -155.10002 90)
		(property "Reference" "TH4A1"
			(at -0.94869 -7.15391 0)
			(unlocked yes)
			(layer "F.SilkS")
			(effects
				(font
					(size 0.7874 0.5842)
					(thickness 0.1524)
				)
				(justify left)
			)
		)
		(property "Value" ""
			(at 0 0 90)
			(layer "F.Fab")
			(effects
				(font
					(size 1.27 1.27)
				)
			)
		)
		(duplicate_pad_numbers_are_jumpers no)
		(fp_poly
			(pts
				(arc
					(start 3.0226 0.68834)
					(mid 3.042235 0.827855)
					(end 3.099562 0.956564)
				)
				(arc
					(start 3.099562 0.956564)
					(mid 4.012804 3.550073)
					(end 3.042158 6.12267)
				)
				(arc
					(start 3.042158 6.12267)
					(mid 0 7.518589)
					(end -3.042158 6.12267)
				)
				(arc
					(start -3.042158 6.12267)
					(mid -4.012854 3.55061)
					(end -3.100324 0.957326)
				)
				(arc
					(start -3.100324 0.957326)
					(mid -3.042498 0.827518)
					(end -3.0226 0.686816)
				)
				(arc
					(start -3.0226 -0.000254)
					(mid -2.137121 -2.137227)
					(end 0 -3.022346)
				)
				(arc
					(start 0 -3.022346)
					(mid 2.137227 -2.136973)
					(end 3.0226 0.000254)
				)
			)
			(stroke
				(width 0)
				(type default)
			)
			(fill no)
			(layer "F.CrtYd")
		)
		(pad "1" thru_hole custom
			(at 0 0 90)
			(size 2.00667 2.00667)
			(drill 0.3048)
			(layers "*.Cu" "*.Mask")
			(remove_unused_layers no)
			(net "GND")
			(clearance -0.889)
			(options
				(clearance outline)
				(anchor circle)
			)
			(primitives
				(gr_poly
					(pts
						(arc
							(start 3.042158 3.874516)
							(mid 0 5.270435)
							(end -3.042158 3.874516)
						)
						(arc
							(start -3.042158 3.874516)
							(mid -4.012854 1.302456)
							(end -3.100324 -1.290828)
						)
						(arc
							(start -3.100324 -1.290828)
							(mid -3.042498 -1.420636)
							(end -3.0226 -1.561338)
						)
						(arc
							(start -3.0226 -2.248408)
							(mid -2.137121 -4.385381)
							(end 0 -5.2705)
						)
						(arc
							(start 0 -5.2705)
							(mid 2.137227 -4.385127)
							(end 3.0226 -2.2479)
						)
						(arc
							(start 3.0226 -1.55956)
							(mid 3.04227 -1.420177)
							(end 3.099562 -1.29159)
						)
						(arc
							(start 3.099562 -1.29159)
							(mid 4.012804 1.301919)
							(end 3.042158 3.874516)
						)
					)
					(width 0)
					(fill yes)
				)
			)
		)
	)
	(footprint ""
		(layer "F.Cu")
		(at 438.4675 -16.129 90)
		(property "Reference" "R1U60"
			(at 0 0 90)
			(layer "F.SilkS")
			(hide yes)
			(effects
				(font
					(size 1.27 1.27)
				)
			)
		)
		(property "Value" ""
			(at 0 0 90)
			(layer "F.Fab")
			(effects
				(font
					(size 1.27 1.27)
				)
			)
		)
		(duplicate_pad_numbers_are_jumpers no)
		(fp_poly
			(pts
				(xy -0.2794 -0.1016) (xy 0.2794 -0.1016) (xy 0.2794 0.9906) (xy -0.2794 0.9906)
			)
			(stroke
				(width 0)
				(type default)
			)
			(fill no)
			(layer "F.CrtYd")
		)
		(fp_line
			(start 0.2794 -0.1016)
			(end -0.2794 -0.1016)
			(stroke
				(width 0.1)
				(type default)
			)
			(layer "F.Fab")
		)
		(fp_line
			(start -0.2794 -0.1016)
			(end -0.2794 0.9906)
			(stroke
				(width 0.1)
				(type default)
			)
			(layer "F.Fab")
		)
		(fp_line
			(start 0.2794 0.9906)
			(end 0.2794 -0.1016)
			(stroke
				(width 0.1)
				(type default)
			)
			(layer "F.Fab")
		)
		(fp_line
			(start -0.2794 0.9906)
			(end 0.2794 0.9906)
			(stroke
				(width 0.1)
				(type default)
			)
			(layer "F.Fab")
		)
		(pad "1" smd rect
			(at 0 0 90)
			(size 0.508 0.508)
			(layers "F.Cu" "F.Mask" "F.Paste")
			(net "H_CPU1_MEMKLM_MEMHOT_G_N")
		)
		(pad "2" smd rect
			(at 0 0.889 90)
			(size 0.508 0.508)
			(layers "F.Cu" "F.Mask" "F.Paste")
			(net "H_CPU1_MEMKLM_MEMHOT_G_R_N")
		)
		(zone
			(layer "F.Cu")
			(hatch none 0.5)
			(connect_pads
				(clearance 0)
			)
			(min_thickness 0.25)
			(keepout
				(tracks allowed)
				(vias not_allowed)
				(pads allowed)
				(copperpour not_allowed)
				(footprints allowed)
			)
			(placement
				(enabled no)
				(sheetname "")
			)
			(fill
				(thermal_gap 0.5)
				(thermal_bridge_width 0.5)
				(island_removal_mode 0)
			)
			(polygon
				(pts
					(xy 438.7215 -15.875) (xy 438.7215 -16.383) (xy 439.1025 -16.383) (xy 439.1025 -15.875)
				)
			)
		)
		(zone
			(layer "F.Cu")
			(hatch none 0.5)
			(connect_pads
				(clearance 0)
			)
			(min_thickness 0.25)
			(keepout
				(tracks not_allowed)
				(vias allowed)
				(pads allowed)
				(copperpour not_allowed)
				(footprints allowed)
			)
			(placement
				(enabled no)
				(sheetname "")
			)
			(fill
				(thermal_gap 0.5)
				(thermal_bridge_width 0.5)
				(island_removal_mode 0)
			)
			(polygon
				(pts
					(xy 439.1025 -15.875) (xy 439.1025 -16.383) (xy 438.7215 -16.383) (xy 438.7215 -15.875)
				)
			)
		)
	)
	(footprint ""
		(layer "F.Cu")
		(at 343.027 -22.64156 180)
		(property "Reference" "R7F18"
			(at 0 0 180)
			(layer "F.SilkS")
			(hide yes)
			(effects
				(font
					(size 1.27 1.27)
				)
			)
		)
		(property "Value" ""
			(at 0 0 180)
			(layer "F.Fab")
			(effects
				(font
					(size 1.27 1.27)
				)
			)
		)
		(duplicate_pad_numbers_are_jumpers no)
		(fp_rect
			(start 0.2794 -0.1016)
			(end -0.2794 0.9906)
			(stroke
				(width 0)
				(type default)
			)
			(fill no)
			(layer "F.CrtYd")
		)
		(fp_line
			(start 0.2794 0.9906)
			(end 0.2794 -0.1016)
			(stroke
				(width 0.1)
				(type default)
			)
			(layer "F.Fab")
		)
		(fp_line
			(start 0.2794 -0.1016)
			(end -0.2794 -0.1016)
			(stroke
				(width 0.1)
				(type default)
			)
			(layer "F.Fab")
		)
		(fp_line
			(start -0.2794 0.9906)
			(end 0.2794 0.9906)
			(stroke
				(width 0.1)
				(type default)
			)
			(layer "F.Fab")
		)
		(fp_line
			(start -0.2794 -0.1016)
			(end -0.2794 0.9906)
			(stroke
				(width 0.1)
				(type default)
			)
			(layer "F.Fab")
		)
		(pad "1" smd rect
			(at 0 0 180)
			(size 0.508 0.508)
			(layers "F.Cu" "F.Mask" "F.Paste")
			(net "VR_COMP_RC_PVPP_ABC")
		)
		(pad "2" smd rect
			(at 0 0.889 180)
			(size 0.508 0.508)
			(layers "F.Cu" "F.Mask" "F.Paste")
			(net "VR_FB_PVPP_ABC")
		)
		(zone
			(layer "F.Cu")
			(hatch none 0.5)
			(connect_pads
				(clearance 0)
			)
			(min_thickness 0.25)
			(keepout
				(tracks allowed)
				(vias not_allowed)
				(pads allowed)
				(copperpour not_allowed)
				(footprints allowed)
			)
			(placement
				(enabled no)
				(sheetname "")
			)
			(fill
				(thermal_gap 0.5)
				(thermal_bridge_width 0.5)
				(island_removal_mode 0)
			)
			(polygon
				(pts
					(xy 342.773 -22.89556) (xy 343.281 -22.89556) (xy 343.281 -23.27656) (xy 342.773 -23.27656)
				)
			)
		)
		(zone
			(layer "F.Cu")
			(hatch none 0.5)
			(connect_pads
				(clearance 0)
			)
			(min_thickness 0.25)
			(keepout
				(tracks not_allowed)
				(vias allowed)
				(pads allowed)
				(copperpour not_allowed)
				(footprints allowed)
			)
			(placement
				(enabled no)
				(sheetname "")
			)
			(fill
				(thermal_gap 0.5)
				(thermal_bridge_width 0.5)
				(island_removal_mode 0)
			)
			(polygon
				(pts
					(xy 342.773 -22.89556) (xy 343.281 -22.89556) (xy 343.281 -23.27656) (xy 342.773 -23.27656)
				)
			)
		)
	)
	(footprint ""
		(layer "F.Cu")
		(at 419.6207 -105.029 90)
		(property "Reference" "R9W19"
			(at -0.8382 -0.67818 90)
			(unlocked yes)
			(layer "F.SilkS")
			(effects
				(font
					(size 0.4064 0.254)
					(thickness 0.1524)
				)
				(justify left)
			)
		)
		(property "Value" ""
			(at 0 0 90)
			(layer "F.Fab")
			(effects
				(font
					(size 1.27 1.27)
				)
			)
		)
		(duplicate_pad_numbers_are_jumpers no)
		(fp_poly
			(pts
				(xy -0.2794 -0.1016) (xy 0.2794 -0.1016) (xy 0.2794 0.9906) (xy -0.2794 0.9906)
			)
			(stroke
				(width 0)
				(type default)
			)
			(fill no)
			(layer "F.CrtYd")
		)
		(fp_line
			(start 0.2794 -0.1016)
			(end -0.2794 -0.1016)
			(stroke
				(width 0.1)
				(type default)
			)
			(layer "F.Fab")
		)
		(fp_line
			(start -0.2794 -0.1016)
			(end -0.2794 0.9906)
			(stroke
				(width 0.1)
				(type default)
			)
			(layer "F.Fab")
		)
		(fp_line
			(start 0.2794 0.9906)
			(end 0.2794 -0.1016)
			(stroke
				(width 0.1)
				(type default)
			)
			(layer "F.Fab")
		)
		(fp_line
			(start -0.2794 0.9906)
			(end 0.2794 0.9906)
			(stroke
				(width 0.1)
				(type default)
			)
			(layer "F.Fab")
		)
		(pad "1" smd rect
			(at 0 0 90)
			(size 0.508 0.508)
			(layers "F.Cu" "F.Mask" "F.Paste")
			(net "PVCCIO_CPU0")
		)
		(pad "2" smd rect
			(at 0 0.889 90)
			(size 0.508 0.508)
			(layers "F.Cu" "F.Mask" "F.Paste")
			(net "SMB_CPU0_PE_HP_GTL_R_SCL")
		)
		(zone
			(layer "F.Cu")
			(hatch none 0.5)
			(connect_pads
				(clearance 0)
			)
			(min_thickness 0.25)
			(keepout
				(tracks allowed)
				(vias not_allowed)
				(pads allowed)
				(copperpour not_allowed)
				(footprints allowed)
			)
			(placement
				(enabled no)
				(sheetname "")
			)
			(fill
				(thermal_gap 0.5)
				(thermal_bridge_width 0.5)
				(island_removal_mode 0)
			)
			(polygon
				(pts
					(xy 419.8747 -104.775) (xy 419.8747 -105.283) (xy 420.2557 -105.283) (xy 420.2557 -104.775)
				)
			)
		)
		(zone
			(layer "F.Cu")
			(hatch none 0.5)
			(connect_pads
				(clearance 0)
			)
			(min_thickness 0.25)
			(keepout
				(tracks not_allowed)
				(vias allowed)
				(pads allowed)
				(copperpour not_allowed)
				(footprints allowed)
			)
			(placement
				(enabled no)
				(sheetname "")
			)
			(fill
				(thermal_gap 0.5)
				(thermal_bridge_width 0.5)
				(island_removal_mode 0)
			)
			(polygon
				(pts
					(xy 420.2557 -104.775) (xy 420.2557 -105.283) (xy 419.8747 -105.283) (xy 419.8747 -104.775)
				)
			)
		)
	)
	(footprint ""
		(layer "F.Cu")
		(at 420.865046 -48.968152)
		(property "Reference" "R25W99"
			(at -0.8382 -0.67818 0)
			(unlocked yes)
			(layer "F.SilkS")
			(effects
				(font
					(size 0.4064 0.254)
					(thickness 0.1524)
				)
				(justify left)
			)
		)
		(property "Value" ""
			(at 0 0 0)
			(layer "F.Fab")
			(effects
				(font
					(size 1.27 1.27)
				)
			)
		)
		(duplicate_pad_numbers_are_jumpers no)
		(fp_poly
			(pts
				(xy -0.2794 -0.1016) (xy 0.2794 -0.1016) (xy 0.2794 0.9906) (xy -0.2794 0.9906)
			)
			(stroke
				(width 0)
				(type default)
			)
			(fill no)
			(layer "F.CrtYd")
		)
		(fp_line
			(start -0.2794 -0.1016)
			(end -0.2794 0.9906)
			(stroke
				(width 0.1)
				(type default)
			)
			(layer "F.Fab")
		)
		(fp_line
			(start -0.2794 0.9906)
			(end 0.2794 0.9906)
			(stroke
				(width 0.1)
				(type default)
			)
			(layer "F.Fab")
		)
		(fp_line
			(start 0.2794 -0.1016)
			(end -0.2794 -0.1016)
			(stroke
				(width 0.1)
				(type default)
			)
			(layer "F.Fab")
		)
		(fp_line
			(start 0.2794 0.9906)
			(end 0.2794 -0.1016)
			(stroke
				(width 0.1)
				(type default)
			)
			(layer "F.Fab")
		)
		(pad "1" smd rect
			(at 0 0)
			(size 0.508 0.508)
			(layers "F.Cu" "F.Mask" "F.Paste")
			(net "P3V3_STBY")
		)
		(pad "2" smd rect
			(at 0 0.889)
			(size 0.508 0.508)
			(layers "F.Cu" "F.Mask" "F.Paste")
			(net "BMC_STRAP_BIT5")
		)
		(zone
			(layer "F.Cu")
			(hatch none 0.5)
			(connect_pads
				(clearance 0)
			)
			(min_thickness 0.25)
			(keepout
				(tracks allowed)
				(vias not_allowed)
				(pads allowed)
				(copperpour not_allowed)
				(footprints allowed)
			)
			(placement
				(enabled no)
				(sheetname "")
			)
			(fill
				(thermal_gap 0.5)
				(thermal_bridge_width 0.5)
				(island_removal_mode 0)
			)
			(polygon
				(pts
					(xy 420.611046 -48.714152) (xy 421.119046 -48.714152) (xy 421.119046 -48.333152) (xy 420.611046 -48.333152)
				)
			)
		)
		(zone
			(layer "F.Cu")
			(hatch none 0.5)
			(connect_pads
				(clearance 0)
			)
			(min_thickness 0.25)
			(keepout
				(tracks not_allowed)
				(vias allowed)
				(pads allowed)
				(copperpour not_allowed)
				(footprints allowed)
			)
			(placement
				(enabled no)
				(sheetname "")
			)
			(fill
				(thermal_gap 0.5)
				(thermal_bridge_width 0.5)
				(island_removal_mode 0)
			)
			(polygon
				(pts
					(xy 420.611046 -48.333152) (xy 421.119046 -48.333152) (xy 421.119046 -48.714152) (xy 420.611046 -48.714152)
				)
			)
		)
	)
)
